# T6G (Grand Teton) — schematic netlist excerpt (pin names and nets, part order shuffled) for the footprints in the layout excerpt that follows; sources: Cadence DE-HDL packaged netlist, KiCad conversion of 04192023_DAF0TMB3IC0_F0TG_MB_C_brd_V02_OCP.brd

C274  Q_CAP  22UF 4V 20% X6S  pkg C0402  page 69 : A = PVDDCR_CPU0_P0 ; B = GND
R327  Q_RES  0 5% CHIP  pkg 0402LF  page 161 : A = SMB_APML_CPU0_MUX2_SCL ; B = SMB_APML_CPU0_SCL

(kicad_pcb
	(version 20260206)
	(generator "pcbnew")
	(generator_version "10.0")
	(general
		(thickness 1.6)
		(legacy_teardrops no)
	)
	(paper "A4")
	(title_block
		(title "04192023_DAF0TMB3IC0_F0TG_MB_C_brd_V02_OCP.brd")
		(comment 1 "Grand Teton / footprints 5171-5172 of 8354")
	)
	(layers
		(0 "F.Cu" signal "TOP")
		(4 "In1.Cu" signal "GND")
		(6 "In2.Cu" signal "IN1")
		(8 "In3.Cu" signal "GND1")
		(10 "In4.Cu" signal "IN2")
		(12 "In5.Cu" signal "GND2")
		(14 "In6.Cu" signal "IN3")
		(16 "In7.Cu" signal "GND3")
		(18 "In8.Cu" signal "VCC")
		(20 "In9.Cu" signal "VCC1")
		(22 "In10.Cu" signal "GND4")
		(24 "In11.Cu" signal "IN4")
		(26 "In12.Cu" signal "GND5")
		(28 "In13.Cu" signal "IN5")
		(30 "In14.Cu" signal "GND6")
		(32 "In15.Cu" signal "IN6")
		(34 "In16.Cu" signal "GND7")
		(2 "B.Cu" signal "BOTTOM")
		(9 "F.Adhes" user "F.Adhesive")
		(11 "B.Adhes" user "B.Adhesive")
		(13 "F.Paste" user "Package Geometry/Pastemask Top")
		(15 "B.Paste" user "Package Geometry/Pastemask Bottom")
		(5 "F.SilkS" user "Ref Des/Silkscreen Top")
		(7 "B.SilkS" user "Ref Des/Silkscreen Bottom")
		(1 "F.Mask" user "Board Geometry/Soldermask Top")
		(3 "B.Mask" user "Board Geometry/Soldermask Bottom")
		(17 "Dwgs.User" user "User.Drawings")
		(19 "Cmts.User" user "User.Comments")
		(21 "Eco1.User" user "User.Eco1")
		(23 "Eco2.User" user "User.Eco2")
		(25 "Edge.Cuts" user "Board Geometry/Outline")
		(27 "Margin" user)
		(31 "F.CrtYd" user "Package Geometry/Place Bound Top")
		(29 "B.CrtYd" user "Package Geometry/Place Bound Bottom")
		(35 "F.Fab" user "Ref Des/Assembly Top")
		(33 "B.Fab" user "Ref Des/Assembly Bottom")
	)
	(footprint ""
		(layer "B.Cu")
		(at 371.551454 -249.36831)
		(property "Reference" "C274"
			(at 0 0 0)
			(layer "B.SilkS")
			(hide yes)
			(effects
				(font
					(size 1.27 1.27)
				)
				(justify mirror)
			)
		)
		(property "Value" ""
			(at 0 0 0)
			(layer "B.Fab")
			(effects
				(font
					(size 1.27 1.27)
				)
				(justify mirror)
			)
		)
		(duplicate_pad_numbers_are_jumpers no)
		(fp_line
			(start -0.7874 -0.4064)
			(end -0.7874 0.4064)
			(stroke
				(width 0.1524)
				(type default)
			)
			(layer "B.SilkS")
		)
		(fp_line
			(start -0.7874 0.4064)
			(end 0.7874 0.4064)
			(stroke
				(width 0.1524)
				(type default)
			)
			(layer "B.SilkS")
		)
		(fp_line
			(start 0.7874 -0.4064)
			(end -0.7874 -0.4064)
			(stroke
				(width 0.1524)
				(type default)
			)
			(layer "B.SilkS")
		)
		(fp_line
			(start 0.7874 0.4064)
			(end 0.7874 -0.4064)
			(stroke
				(width 0.1524)
				(type default)
			)
			(layer "B.SilkS")
		)
		(fp_line
			(start -0.67945 -0.3048)
			(end -0.67945 0.3048)
			(stroke
				(width 0.1)
				(type default)
			)
			(layer "B.Fab")
		)
		(fp_line
			(start -0.67945 0.3048)
			(end -0.120396 0.3048)
			(stroke
				(width 0.1)
				(type default)
			)
			(layer "B.Fab")
		)
		(fp_line
			(start -0.12065 -0.3048)
			(end -0.67945 -0.3048)
			(stroke
				(width 0.1)
				(type default)
			)
			(layer "B.Fab")
		)
		(fp_line
			(start -0.12065 -0.2794)
			(end -0.12065 -0.3048)
			(stroke
				(width 0.1)
				(type default)
			)
			(layer "B.Fab")
		)
		(fp_line
			(start -0.120396 0.2794)
			(end 0.12065 0.2794)
			(stroke
				(width 0.1)
				(type default)
			)
			(layer "B.Fab")
		)
		(fp_line
			(start -0.120396 0.3048)
			(end -0.120396 0.2794)
			(stroke
				(width 0.1)
				(type default)
			)
			(layer "B.Fab")
		)
		(fp_line
			(start 0.12065 -0.305054)
			(end 0.12065 -0.2794)
			(stroke
				(width 0.1)
				(type default)
			)
			(layer "B.Fab")
		)
		(fp_line
			(start 0.12065 -0.2794)
			(end -0.12065 -0.2794)
			(stroke
				(width 0.1)
				(type default)
			)
			(layer "B.Fab")
		)
		(fp_line
			(start 0.12065 0.2794)
			(end 0.12065 0.3048)
			(stroke
				(width 0.1)
				(type default)
			)
			(layer "B.Fab")
		)
		(fp_line
			(start 0.12065 0.3048)
			(end 0.67945 0.3048)
			(stroke
				(width 0.1)
				(type default)
			)
			(layer "B.Fab")
		)
		(fp_line
			(start 0.67945 -0.305054)
			(end 0.12065 -0.305054)
			(stroke
				(width 0.1)
				(type default)
			)
			(layer "B.Fab")
		)
		(fp_line
			(start 0.67945 0.3048)
			(end 0.67945 -0.305054)
			(stroke
				(width 0.1)
				(type default)
			)
			(layer "B.Fab")
		)
		(pad "1" smd circle
			(at 0.40005 0 180)
			(size 0 0)
			(layers "B.Cu" "B.Mask" "B.Paste")
			(net "PVDDCR_CPU0_P0")
		)
		(pad "2" smd circle
			(at -0.40005 0 180)
			(size 0 0)
			(layers "B.Cu" "B.Mask" "B.Paste")
			(net "GND")
		)
	)
	(footprint ""
		(layer "B.Cu")
		(at 236.8169 -249.555 180)
		(property "Reference" "R327"
			(at 0 0 0)
			(layer "B.SilkS")
			(hide yes)
			(effects
				(font
					(size 1.27 1.27)
				)
				(justify mirror)
			)
		)
		(property "Value" ""
			(at 0 0 0)
			(layer "B.Fab")
			(effects
				(font
					(size 1.27 1.27)
				)
				(justify mirror)
			)
		)
		(duplicate_pad_numbers_are_jumpers no)
		(fp_line
			(start 0.7874 0.4064)
			(end 0.7874 -0.4064)
			(stroke
				(width 0.1524)
				(type default)
			)
			(layer "B.SilkS")
		)
		(fp_line
			(start 0.7874 -0.4064)
			(end -0.7874 -0.4064)
			(stroke
				(width 0.1524)
				(type default)
			)
			(layer "B.SilkS")
		)
		(fp_line
			(start -0.7874 0.4064)
			(end 0.7874 0.4064)
			(stroke
				(width 0.1524)
				(type default)
			)
			(layer "B.SilkS")
		)
		(fp_line
			(start -0.7874 -0.4064)
			(end -0.7874 0.4064)
			(stroke
				(width 0.1524)
				(type default)
			)
			(layer "B.SilkS")
		)
		(fp_line
			(start 0.67945 0.3048)
			(end 0.67945 -0.305054)
			(stroke
				(width 0.1)
				(type default)
			)
			(layer "B.Fab")
		)
		(fp_line
			(start 0.67945 -0.305054)
			(end 0.12065 -0.305054)
			(stroke
				(width 0.1)
				(type default)
			)
			(layer "B.Fab")
		)
		(fp_line
			(start 0.12065 0.3048)
			(end 0.67945 0.3048)
			(stroke
				(width 0.1)
				(type default)
			)
			(layer "B.Fab")
		)
		(fp_line
			(start 0.12065 0.2794)
			(end 0.12065 0.3048)
			(stroke
				(width 0.1)
				(type default)
			)
			(layer "B.Fab")
		)
		(fp_line
			(start 0.12065 -0.2794)
			(end -0.12065 -0.2794)
			(stroke
				(width 0.1)
				(type default)
			)
			(layer "B.Fab")
		)
		(fp_line
			(start 0.12065 -0.305054)
			(end 0.12065 -0.2794)
			(stroke
				(width 0.1)
				(type default)
			)
			(layer "B.Fab")
		)
		(fp_line
			(start -0.120396 0.3048)
			(end -0.120396 0.2794)
			(stroke
				(width 0.1)
				(type default)
			)
			(layer "B.Fab")
		)
		(fp_line
			(start -0.120396 0.2794)
			(end 0.12065 0.2794)
			(stroke
				(width 0.1)
				(type default)
			)
			(layer "B.Fab")
		)
		(fp_line
			(start -0.12065 -0.2794)
			(end -0.12065 -0.3048)
			(stroke
				(width 0.1)
				(type default)
			)
			(layer "B.Fab")
		)
		(fp_line
			(start -0.12065 -0.3048)
			(end -0.67945 -0.3048)
			(stroke
				(width 0.1)
				(type default)
			)
			(layer "B.Fab")
		)
		(fp_line
			(start -0.67945 0.3048)
			(end -0.120396 0.3048)
			(stroke
				(width 0.1)
				(type default)
			)
			(layer "B.Fab")
		)
		(fp_line
			(start -0.67945 -0.3048)
			(end -0.67945 0.3048)
			(stroke
				(width 0.1)
				(type default)
			)
			(layer "B.Fab")
		)
		(pad "1" smd rect
			(at 0.40005 0 180)
			(size 0.4572 0.508)
			(layers "B.Cu" "B.Mask" "B.Paste")
			(net "SMB_APML_CPU0_MUX2_SCL")
		)
		(pad "2" smd rect
			(at -0.40005 0 180)
			(size 0.4572 0.508)
			(layers "B.Cu" "B.Mask" "B.Paste")
			(net "SMB_APML_CPU0_SCL")
		)
	)
)
